(kicad_pcb
	(version 20260206)
	(generator "pcbnew")
	(generator_version "10.0")
	(general
		(thickness 1.6)
		(legacy_teardrops no)
	)
	(paper "A4")
	(title_block
		(title "v1-chassis-manager — T6M_CM_d_v01_1031_1645.brd")
		(comment 1 "Open CloudServer (Microsoft) / footprints 2501-2510 of 2512")
	)
	(layers
		(0 "F.Cu" signal "TOP")
		(4 "In1.Cu" signal "GND1")
		(6 "In2.Cu" signal "IN1")
		(8 "In3.Cu" signal "VCC1")
		(10 "In4.Cu" signal "VCC2")
		(12 "In5.Cu" signal "GND2")
		(14 "In6.Cu" signal "IN2")
		(16 "In7.Cu" signal "IN3")
		(18 "In8.Cu" signal "GND3")
		(2 "B.Cu" signal "BOTTOM")
		(9 "F.Adhes" user "F.Adhesive")
		(11 "B.Adhes" user "B.Adhesive")
		(13 "F.Paste" user "Package Geometry/Pastemask Top")
		(15 "B.Paste" user "Package Geometry/Pastemask Bottom")
		(5 "F.SilkS" user "Ref Des/Silkscreen Top")
		(7 "B.SilkS" user "Ref Des/Silkscreen Bottom")
		(1 "F.Mask" user "Board Geometry/Soldermask Top")
		(3 "B.Mask" user "Board Geometry/Soldermask Bottom")
		(17 "Dwgs.User" user "User.Drawings")
		(19 "Cmts.User" user "User.Comments")
		(21 "Eco1.User" user "User.Eco1")
		(23 "Eco2.User" user "User.Eco2")
		(25 "Edge.Cuts" user "Board Geometry/Outline")
		(27 "Margin" user)
		(31 "F.CrtYd" user "Package Geometry/Place Bound Top")
		(29 "B.CrtYd" user "Package Geometry/Place Bound Bottom")
		(35 "F.Fab" user "Ref Des/Assembly Top")
		(33 "B.Fab" user "Ref Des/Assembly Bottom")
	)
	(footprint ""
		(layer "B.Cu")
		(at 133.08076 -187.872624 90)
		(property "Reference" "R962"
			(at 4.565396 -1.244092 270)
			(unlocked yes)
			(layer "B.SilkS")
			(effects
				(font
					(size 0.7874 0.5842)
					(thickness 0.1524)
				)
				(justify left mirror)
			)
		)
		(property "Value" ""
			(at 0 0 90)
			(layer "B.Fab")
			(effects
				(font
					(size 1.27 1.27)
				)
				(justify mirror)
			)
		)
		(duplicate_pad_numbers_are_jumpers no)
		(fp_line
			(start 0.7874 -0.4064)
			(end -0.7874 -0.4064)
			(stroke
				(width 0.1524)
				(type default)
			)
			(layer "B.SilkS")
		)
		(fp_line
			(start -0.7874 -0.4064)
			(end -0.7874 0.4064)
			(stroke
				(width 0.1524)
				(type default)
			)
			(layer "B.SilkS")
		)
		(fp_line
			(start 0.7874 0.4064)
			(end 0.7874 -0.4064)
			(stroke
				(width 0.1524)
				(type default)
			)
			(layer "B.SilkS")
		)
		(fp_line
			(start -0.7874 0.4064)
			(end 0.7874 0.4064)
			(stroke
				(width 0.1524)
				(type default)
			)
			(layer "B.SilkS")
		)
		(fp_poly
			(pts
				(xy 0.508 0.2794) (xy 0.508 0.2286) (xy 0.635 0.2286) (xy 0.635 -0.254) (xy 0.5334 -0.254) (xy 0.5334 -0.2794)
				(xy -0.5334 -0.2794) (xy -0.5334 -0.254) (xy -0.635 -0.254) (xy -0.635 0.254) (xy -0.5334 0.254)
				(xy -0.5334 0.2794)
			)
			(stroke
				(width 0)
				(type default)
			)
			(fill no)
			(layer "B.CrtYd")
		)
		(pad "1" smd rect
			(at -0.40005 0 270)
			(size 0.4572 0.508)
			(layers "B.Cu" "B.Mask" "B.Paste")
			(net "UART_T9_NODE2_RXD")
		)
		(pad "2" smd rect
			(at 0.40005 0 270)
			(size 0.4572 0.508)
			(layers "B.Cu" "B.Mask" "B.Paste")
			(net "UART_T9_NODE2_RXD_R")
		)
	)
	(footprint ""
		(layer "B.Cu")
		(at 60.81776 -185.205624 90)
		(property "Reference" "R916"
			(at 4.15163 0.143764 270)
			(unlocked yes)
			(layer "B.SilkS")
			(effects
				(font
					(size 0.7874 0.5842)
					(thickness 0.1524)
				)
				(justify left mirror)
			)
		)
		(property "Value" ""
			(at 0 0 90)
			(layer "B.Fab")
			(effects
				(font
					(size 1.27 1.27)
				)
				(justify mirror)
			)
		)
		(duplicate_pad_numbers_are_jumpers no)
		(fp_line
			(start 0.7874 -0.4064)
			(end -0.7874 -0.4064)
			(stroke
				(width 0.1524)
				(type default)
			)
			(layer "B.SilkS")
		)
		(fp_line
			(start -0.7874 -0.4064)
			(end -0.7874 0.4064)
			(stroke
				(width 0.1524)
				(type default)
			)
			(layer "B.SilkS")
		)
		(fp_line
			(start 0.7874 0.4064)
			(end 0.7874 -0.4064)
			(stroke
				(width 0.1524)
				(type default)
			)
			(layer "B.SilkS")
		)
		(fp_line
			(start -0.7874 0.4064)
			(end 0.7874 0.4064)
			(stroke
				(width 0.1524)
				(type default)
			)
			(layer "B.SilkS")
		)
		(fp_poly
			(pts
				(xy 0.508 0.2794) (xy 0.508 0.2286) (xy 0.635 0.2286) (xy 0.635 -0.254) (xy 0.5334 -0.254) (xy 0.5334 -0.2794)
				(xy -0.5334 -0.2794) (xy -0.5334 -0.254) (xy -0.635 -0.254) (xy -0.635 0.254) (xy -0.5334 0.254)
				(xy -0.5334 0.2794)
			)
			(stroke
				(width 0)
				(type default)
			)
			(fill no)
			(layer "B.CrtYd")
		)
		(pad "1" smd rect
			(at -0.40005 0 270)
			(size 0.4572 0.508)
			(layers "B.Cu" "B.Mask" "B.Paste")
			(net "UART_T1_NODE2_TXD")
		)
		(pad "2" smd rect
			(at 0.40005 0 270)
			(size 0.4572 0.508)
			(layers "B.Cu" "B.Mask" "B.Paste")
			(net "UART_T1_NODE2_TXD_R")
		)
	)
	(footprint ""
		(layer "B.Cu")
		(at 74.27468 -165.307518 90)
		(property "Reference" "R911"
			(at 0.469646 -2.643632 270)
			(unlocked yes)
			(layer "B.SilkS")
			(effects
				(font
					(size 0.7874 0.5842)
					(thickness 0.1524)
				)
				(justify left mirror)
			)
		)
		(property "Value" ""
			(at 0 0 90)
			(layer "B.Fab")
			(effects
				(font
					(size 1.27 1.27)
				)
				(justify mirror)
			)
		)
		(duplicate_pad_numbers_are_jumpers no)
		(fp_line
			(start 0.7874 -0.4064)
			(end -0.7874 -0.4064)
			(stroke
				(width 0.1524)
				(type default)
			)
			(layer "B.SilkS")
		)
		(fp_line
			(start -0.7874 -0.4064)
			(end -0.7874 0.4064)
			(stroke
				(width 0.1524)
				(type default)
			)
			(layer "B.SilkS")
		)
		(fp_line
			(start 0.7874 0.4064)
			(end 0.7874 -0.4064)
			(stroke
				(width 0.1524)
				(type default)
			)
			(layer "B.SilkS")
		)
		(fp_line
			(start -0.7874 0.4064)
			(end 0.7874 0.4064)
			(stroke
				(width 0.1524)
				(type default)
			)
			(layer "B.SilkS")
		)
		(fp_poly
			(pts
				(xy 0.508 0.2794) (xy 0.508 0.2286) (xy 0.635 0.2286) (xy 0.635 -0.254) (xy 0.5334 -0.254) (xy 0.5334 -0.2794)
				(xy -0.5334 -0.2794) (xy -0.5334 -0.254) (xy -0.635 -0.254) (xy -0.635 0.254) (xy -0.5334 0.254)
				(xy -0.5334 0.2794)
			)
			(stroke
				(width 0)
				(type default)
			)
			(fill no)
			(layer "B.CrtYd")
		)
		(pad "1" smd rect
			(at -0.40005 0 270)
			(size 0.4572 0.508)
			(layers "B.Cu" "B.Mask" "B.Paste")
			(net "UART_T3_NODE1_TXD")
		)
		(pad "2" smd rect
			(at 0.40005 0 270)
			(size 0.4572 0.508)
			(layers "B.Cu" "B.Mask" "B.Paste")
			(net "UART_T3_NODE1_TXD_R")
		)
	)
	(footprint ""
		(layer "B.Cu")
		(at 47.977044 -140.29563 90)
		(property "Reference" "C236"
			(at 1.116584 0.602996 270)
			(unlocked yes)
			(layer "B.SilkS")
			(effects
				(font
					(size 0.7874 0.5842)
					(thickness 0.1524)
				)
				(justify left mirror)
			)
		)
		(property "Value" ""
			(at 0 0 90)
			(layer "B.Fab")
			(effects
				(font
					(size 1.27 1.27)
				)
				(justify mirror)
			)
		)
		(duplicate_pad_numbers_are_jumpers no)
		(fp_line
			(start 0.7874 -0.4064)
			(end -0.7874 -0.4064)
			(stroke
				(width 0.1524)
				(type default)
			)
			(layer "B.SilkS")
		)
		(fp_line
			(start -0.7874 -0.4064)
			(end -0.7874 0.4064)
			(stroke
				(width 0.1524)
				(type default)
			)
			(layer "B.SilkS")
		)
		(fp_line
			(start 0 0.381)
			(end 0 -0.381)
			(stroke
				(width 0.1524)
				(type default)
			)
			(layer "B.SilkS")
		)
		(fp_line
			(start 0.7874 0.4064)
			(end 0.7874 -0.4064)
			(stroke
				(width 0.1524)
				(type default)
			)
			(layer "B.SilkS")
		)
		(fp_line
			(start -0.7874 0.4064)
			(end 0.7874 0.4064)
			(stroke
				(width 0.1524)
				(type default)
			)
			(layer "B.SilkS")
		)
		(fp_poly
			(pts
				(xy 0.5334 0.254) (xy 0.635 0.254) (xy 0.635 0.2286) (xy 0.635 -0.254) (xy 0.5334 -0.254) (xy 0.5334 -0.2794)
				(xy -0.5334 -0.2794) (xy -0.5334 -0.254) (xy -0.635 -0.254) (xy -0.635 0.254) (xy -0.5334 0.254)
				(xy -0.5334 0.2794) (xy 0.508 0.2794) (xy 0.5334 0.2794)
			)
			(stroke
				(width 0)
				(type default)
			)
			(fill no)
			(layer "B.CrtYd")
		)
		(pad "1" smd rect
			(at -0.40005 0 270)
			(size 0.4572 0.508)
			(layers "B.Cu" "B.Mask" "B.Paste")
			(net "P1V538_BMC_NODE1")
		)
		(pad "2" smd rect
			(at 0.40005 0 270)
			(size 0.4572 0.508)
			(layers "B.Cu" "B.Mask" "B.Paste")
			(net "GND")
		)
	)
	(footprint ""
		(layer "B.Cu")
		(at 121.40184 -143.940276 180)
		(property "Reference" "C186"
			(at 1.136396 1.219962 0)
			(unlocked yes)
			(layer "B.SilkS")
			(effects
				(font
					(size 0.7874 0.5842)
					(thickness 0.1524)
				)
				(justify left mirror)
			)
		)
		(property "Value" ""
			(at 0 0 0)
			(layer "B.Fab")
			(effects
				(font
					(size 1.27 1.27)
				)
				(justify mirror)
			)
		)
		(duplicate_pad_numbers_are_jumpers no)
		(fp_line
			(start 0.7874 0.406146)
			(end 0.7874 -0.406146)
			(stroke
				(width 0.1524)
				(type default)
			)
			(layer "B.SilkS")
		)
		(fp_line
			(start 0.7874 -0.406146)
			(end -0.7874 -0.406146)
			(stroke
				(width 0.1524)
				(type default)
			)
			(layer "B.SilkS")
		)
		(fp_line
			(start 0 0.381)
			(end 0 -0.381)
			(stroke
				(width 0.1524)
				(type default)
			)
			(layer "B.SilkS")
		)
		(fp_line
			(start -0.7874 0.406146)
			(end 0.7874 0.406146)
			(stroke
				(width 0.1524)
				(type default)
			)
			(layer "B.SilkS")
		)
		(fp_line
			(start -0.7874 -0.406146)
			(end -0.7874 0.406146)
			(stroke
				(width 0.1524)
				(type default)
			)
			(layer "B.SilkS")
		)
		(fp_poly
			(pts
				(xy 0.5334 0.254) (xy 0.635 0.254) (xy 0.635 0.2286) (xy 0.635 -0.254) (xy 0.5334 -0.254) (xy 0.5334 -0.2794)
				(xy -0.5334 -0.2794) (xy -0.5334 -0.254) (xy -0.635 -0.254) (xy -0.635 0.254) (xy -0.5334 0.254)
				(xy -0.5334 0.2794) (xy 0.508 0.2794) (xy 0.5334 0.2794)
			)
			(stroke
				(width 0)
				(type default)
			)
			(fill no)
			(layer "B.CrtYd")
		)
		(pad "1" smd rect
			(at -0.40005 0)
			(size 0.4572 0.508)
			(layers "B.Cu" "B.Mask" "B.Paste")
			(net "P2E_CPU_PCIE_SW_NODE1_RX_C_DN")
		)
		(pad "2" smd rect
			(at 0.40005 0)
			(size 0.4572 0.508)
			(layers "B.Cu" "B.Mask" "B.Paste")
			(net "P2E_CPU_PCIE_SW_NODE1_RX_DN")
		)
	)
	(footprint ""
		(layer "B.Cu")
		(at 76.487274 -94.131384 -90)
		(property "Reference" "R94"
			(at 3.075432 -0.409448 270)
			(unlocked yes)
			(layer "B.SilkS")
			(effects
				(font
					(size 0.7874 0.5842)
					(thickness 0.1524)
				)
				(justify left mirror)
			)
		)
		(property "Value" ""
			(at 0 0 90)
			(layer "B.Fab")
			(effects
				(font
					(size 1.27 1.27)
				)
				(justify mirror)
			)
		)
		(duplicate_pad_numbers_are_jumpers no)
		(fp_line
			(start -0.7874 0.4064)
			(end 0.7874 0.4064)
			(stroke
				(width 0.1524)
				(type default)
			)
			(layer "B.SilkS")
		)
		(fp_line
			(start 0.7874 0.4064)
			(end 0.7874 -0.4064)
			(stroke
				(width 0.1524)
				(type default)
			)
			(layer "B.SilkS")
		)
		(fp_line
			(start -0.7874 -0.4064)
			(end -0.7874 0.4064)
			(stroke
				(width 0.1524)
				(type default)
			)
			(layer "B.SilkS")
		)
		(fp_line
			(start 0.7874 -0.4064)
			(end -0.7874 -0.4064)
			(stroke
				(width 0.1524)
				(type default)
			)
			(layer "B.SilkS")
		)
		(fp_poly
			(pts
				(xy 0.508 0.2794) (xy 0.508 0.2286) (xy 0.635 0.2286) (xy 0.635 -0.254) (xy 0.5334 -0.254) (xy 0.5334 -0.2794)
				(xy -0.5334 -0.2794) (xy -0.5334 -0.254) (xy -0.635 -0.254) (xy -0.635 0.254) (xy -0.5334 0.254)
				(xy -0.5334 0.2794)
			)
			(stroke
				(width 0)
				(type default)
			)
			(fill no)
			(layer "B.CrtYd")
		)
		(pad "1" smd rect
			(at -0.40005 0 90)
			(size 0.4572 0.508)
			(layers "B.Cu" "B.Mask" "B.Paste")
			(net "P3V3_NODE1")
		)
		(pad "2" smd rect
			(at 0.40005 0 90)
			(size 0.4572 0.508)
			(layers "B.Cu" "B.Mask" "B.Paste")
			(net "NODE1_BIOS_MB_REV_ID2")
		)
	)
	(footprint ""
		(layer "B.Cu")
		(at 39.067486 -141.034262 180)
		(property "Reference" "C234"
			(at 2.529332 0.000254 0)
			(unlocked yes)
			(layer "B.SilkS")
			(effects
				(font
					(size 0.7874 0.5842)
					(thickness 0.1524)
				)
				(justify left mirror)
			)
		)
		(property "Value" ""
			(at 0 0 0)
			(layer "B.Fab")
			(effects
				(font
					(size 1.27 1.27)
				)
				(justify mirror)
			)
		)
		(duplicate_pad_numbers_are_jumpers no)
		(fp_line
			(start 0.7874 0.4064)
			(end 0.7874 -0.4064)
			(stroke
				(width 0.1524)
				(type default)
			)
			(layer "B.SilkS")
		)
		(fp_line
			(start 0.7874 -0.4064)
			(end -0.7874 -0.4064)
			(stroke
				(width 0.1524)
				(type default)
			)
			(layer "B.SilkS")
		)
		(fp_line
			(start 0 0.381)
			(end 0 -0.381)
			(stroke
				(width 0.1524)
				(type default)
			)
			(layer "B.SilkS")
		)
		(fp_line
			(start -0.7874 0.4064)
			(end 0.7874 0.4064)
			(stroke
				(width 0.1524)
				(type default)
			)
			(layer "B.SilkS")
		)
		(fp_line
			(start -0.7874 -0.4064)
			(end -0.7874 0.4064)
			(stroke
				(width 0.1524)
				(type default)
			)
			(layer "B.SilkS")
		)
		(fp_poly
			(pts
				(xy 0.5334 0.254) (xy 0.635 0.254) (xy 0.635 0.2286) (xy 0.635 -0.254) (xy 0.5334 -0.254) (xy 0.5334 -0.2794)
				(xy -0.5334 -0.2794) (xy -0.5334 -0.254) (xy -0.635 -0.254) (xy -0.635 0.254) (xy -0.5334 0.254)
				(xy -0.5334 0.2794) (xy 0.508 0.2794) (xy 0.5334 0.2794)
			)
			(stroke
				(width 0)
				(type default)
			)
			(fill no)
			(layer "B.CrtYd")
		)
		(pad "1" smd rect
			(at -0.40005 0)
			(size 0.4572 0.508)
			(layers "B.Cu" "B.Mask" "B.Paste")
			(net "P1V538_BMC_NODE1")
		)
		(pad "2" smd rect
			(at 0.40005 0)
			(size 0.4572 0.508)
			(layers "B.Cu" "B.Mask" "B.Paste")
			(net "GND")
		)
	)
	(footprint ""
		(layer "B.Cu")
		(at 71.10476 -185.129424 -90)
		(property "Reference" "C683"
			(at -4.15163 0.051562 270)
			(unlocked yes)
			(layer "B.SilkS")
			(effects
				(font
					(size 0.7874 0.5842)
					(thickness 0.1524)
				)
				(justify left mirror)
			)
		)
		(property "Value" ""
			(at 0 0 90)
			(layer "B.Fab")
			(effects
				(font
					(size 1.27 1.27)
				)
				(justify mirror)
			)
		)
		(duplicate_pad_numbers_are_jumpers no)
		(fp_line
			(start -0.7874 0.4064)
			(end 0.7874 0.4064)
			(stroke
				(width 0.1524)
				(type default)
			)
			(layer "B.SilkS")
		)
		(fp_line
			(start 0.7874 0.4064)
			(end 0.7874 -0.4064)
			(stroke
				(width 0.1524)
				(type default)
			)
			(layer "B.SilkS")
		)
		(fp_line
			(start 0 0.381)
			(end 0 -0.381)
			(stroke
				(width 0.1524)
				(type default)
			)
			(layer "B.SilkS")
		)
		(fp_line
			(start -0.7874 -0.4064)
			(end -0.7874 0.4064)
			(stroke
				(width 0.1524)
				(type default)
			)
			(layer "B.SilkS")
		)
		(fp_line
			(start 0.7874 -0.4064)
			(end -0.7874 -0.4064)
			(stroke
				(width 0.1524)
				(type default)
			)
			(layer "B.SilkS")
		)
		(fp_poly
			(pts
				(xy 0.5334 0.254) (xy 0.635 0.254) (xy 0.635 0.2286) (xy 0.635 -0.254) (xy 0.5334 -0.254) (xy 0.5334 -0.2794)
				(xy -0.5334 -0.2794) (xy -0.5334 -0.254) (xy -0.635 -0.254) (xy -0.635 0.254) (xy -0.5334 0.254)
				(xy -0.5334 0.2794) (xy 0.508 0.2794) (xy 0.5334 0.2794)
			)
			(stroke
				(width 0)
				(type default)
			)
			(fill no)
			(layer "B.CrtYd")
		)
		(pad "1" smd rect
			(at -0.40005 0 90)
			(size 0.4572 0.508)
			(layers "B.Cu" "B.Mask" "B.Paste")
			(net "UART_T3_NODE3_RXD")
		)
		(pad "2" smd rect
			(at 0.40005 0 90)
			(size 0.4572 0.508)
			(layers "B.Cu" "B.Mask" "B.Paste")
			(net "GND")
		)
	)
	(footprint ""
		(layer "B.Cu")
		(at 165.011608 -182.035196 180)
		(property "Reference" "R1174"
			(at -6.724904 9.031224 0)
			(unlocked yes)
			(layer "B.SilkS")
			(effects
				(font
					(size 0.7874 0.5842)
					(thickness 0.1524)
				)
				(justify left mirror)
			)
		)
		(property "Value" ""
			(at 0 0 0)
			(layer "B.Fab")
			(effects
				(font
					(size 1.27 1.27)
				)
				(justify mirror)
			)
		)
		(duplicate_pad_numbers_are_jumpers no)
		(fp_line
			(start 0.7874 0.4064)
			(end 0.7874 -0.4064)
			(stroke
				(width 0.1524)
				(type default)
			)
			(layer "B.SilkS")
		)
		(fp_line
			(start 0.7874 -0.4064)
			(end -0.7874 -0.4064)
			(stroke
				(width 0.1524)
				(type default)
			)
			(layer "B.SilkS")
		)
		(fp_line
			(start -0.7874 0.4064)
			(end 0.7874 0.4064)
			(stroke
				(width 0.1524)
				(type default)
			)
			(layer "B.SilkS")
		)
		(fp_line
			(start -0.7874 -0.4064)
			(end -0.7874 0.4064)
			(stroke
				(width 0.1524)
				(type default)
			)
			(layer "B.SilkS")
		)
		(fp_poly
			(pts
				(xy 0.508 0.2794) (xy 0.508 0.2286) (xy 0.635 0.2286) (xy 0.635 -0.254) (xy 0.5334 -0.254) (xy 0.5334 -0.2794)
				(xy -0.5334 -0.2794) (xy -0.5334 -0.254) (xy -0.635 -0.254) (xy -0.635 0.254) (xy -0.5334 0.254)
				(xy -0.5334 0.2794)
			)
			(stroke
				(width 0)
				(type default)
			)
			(fill no)
			(layer "B.CrtYd")
		)
		(pad "1" smd rect
			(at -0.40005 0)
			(size 0.4572 0.508)
			(layers "B.Cu" "B.Mask" "B.Paste")
			(net "CPLD_UART_RX_P4")
		)
		(pad "2" smd rect
			(at 0.40005 0)
			(size 0.4572 0.508)
			(layers "B.Cu" "B.Mask" "B.Paste")
			(net "GND")
		)
	)
	(footprint ""
		(layer "B.Cu")
		(at 125.917452 -138.53795 -90)
		(property "Reference" "C897"
			(at 3.90906 0.573786 270)
			(unlocked yes)
			(layer "B.SilkS")
			(effects
				(font
					(size 0.7874 0.5842)
					(thickness 0.1524)
				)
				(justify left mirror)
			)
		)
		(property "Value" ""
			(at 0 0 90)
			(layer "B.Fab")
			(effects
				(font
					(size 1.27 1.27)
				)
				(justify mirror)
			)
		)
		(duplicate_pad_numbers_are_jumpers no)
		(fp_line
			(start -0.7874 0.4064)
			(end 0.7874 0.4064)
			(stroke
				(width 0.1524)
				(type default)
			)
			(layer "B.SilkS")
		)
		(fp_line
			(start 0.7874 0.4064)
			(end 0.7874 -0.4064)
			(stroke
				(width 0.1524)
				(type default)
			)
			(layer "B.SilkS")
		)
		(fp_line
			(start 0 0.381)
			(end 0 -0.381)
			(stroke
				(width 0.1524)
				(type default)
			)
			(layer "B.SilkS")
		)
		(fp_line
			(start -0.7874 -0.4064)
			(end -0.7874 0.4064)
			(stroke
				(width 0.1524)
				(type default)
			)
			(layer "B.SilkS")
		)
		(fp_line
			(start 0.7874 -0.4064)
			(end -0.7874 -0.4064)
			(stroke
				(width 0.1524)
				(type default)
			)
			(layer "B.SilkS")
		)
		(fp_poly
			(pts
				(xy 0.5334 0.254) (xy 0.635 0.254) (xy 0.635 0.2286) (xy 0.635 -0.254) (xy 0.5334 -0.254) (xy 0.5334 -0.2794)
				(xy -0.5334 -0.2794) (xy -0.5334 -0.254) (xy -0.635 -0.254) (xy -0.635 0.254) (xy -0.5334 0.254)
				(xy -0.5334 0.2794) (xy 0.508 0.2794) (xy 0.5334 0.2794)
			)
			(stroke
				(width 0)
				(type default)
			)
			(fill no)
			(layer "B.CrtYd")
		)
		(pad "1" smd rect
			(at -0.40005 0 90)
			(size 0.4572 0.508)
			(layers "B.Cu" "B.Mask" "B.Paste")
			(net "P1V0_PCI_SW_A")
		)
		(pad "2" smd rect
			(at 0.40005 0 90)
			(size 0.4572 0.508)
			(layers "B.Cu" "B.Mask" "B.Paste")
			(net "GND")
		)
	)
)
